M48
INCH,TZ
T01C.001
T02C.01
T03C.012
T04C.014
T05C.01417
T06C.016
T07C.02
T08C.02913
T09C.035
T010C.037
T011C.04015
T012C.053
T013C.071
T014C.086
T015C.099
T016C.111
T017C.119
T018C.126
T019C.138
T020C.14
T021C.404
;EXTENTS: -110.645 -113.569 146.193 133.539 
;LEADER: 12 
;HEADER: 
;CODE  : ASCII 
;FILE  : 16317-1.rou for board 16317-1.brd
%
G90
F1
M16
G40
M30
